(kicad_pcb
	(version 20260206)
	(generator "pcbnew")
	(generator_version "10.0")
	(general
		(thickness 1.6)
		(legacy_teardrops no)
	)
	(paper "A4")
	(title_block
		(title "04192023_DAF0TMB3IC0_F0TG_MB_C_brd_V02_OCP.brd")
		(comment 1 "Grand Teton / footprints 5930-5936 of 8354")
	)
	(layers
		(0 "F.Cu" signal "TOP")
		(4 "In1.Cu" signal "GND")
		(6 "In2.Cu" signal "IN1")
		(8 "In3.Cu" signal "GND1")
		(10 "In4.Cu" signal "IN2")
		(12 "In5.Cu" signal "GND2")
		(14 "In6.Cu" signal "IN3")
		(16 "In7.Cu" signal "GND3")
		(18 "In8.Cu" signal "VCC")
		(20 "In9.Cu" signal "VCC1")
		(22 "In10.Cu" signal "GND4")
		(24 "In11.Cu" signal "IN4")
		(26 "In12.Cu" signal "GND5")
		(28 "In13.Cu" signal "IN5")
		(30 "In14.Cu" signal "GND6")
		(32 "In15.Cu" signal "IN6")
		(34 "In16.Cu" signal "GND7")
		(2 "B.Cu" signal "BOTTOM")
		(9 "F.Adhes" user "F.Adhesive")
		(11 "B.Adhes" user "B.Adhesive")
		(13 "F.Paste" user "Package Geometry/Pastemask Top")
		(15 "B.Paste" user "Package Geometry/Pastemask Bottom")
		(5 "F.SilkS" user "Ref Des/Silkscreen Top")
		(7 "B.SilkS" user "Ref Des/Silkscreen Bottom")
		(1 "F.Mask" user "Board Geometry/Soldermask Top")
		(3 "B.Mask" user "Board Geometry/Soldermask Bottom")
		(17 "Dwgs.User" user "User.Drawings")
		(19 "Cmts.User" user "User.Comments")
		(21 "Eco1.User" user "User.Eco1")
		(23 "Eco2.User" user "User.Eco2")
		(25 "Edge.Cuts" user "Board Geometry/Outline")
		(27 "Margin" user)
		(31 "F.CrtYd" user "Package Geometry/Place Bound Top")
		(29 "B.CrtYd" user "Package Geometry/Place Bound Bottom")
		(35 "F.Fab" user "Ref Des/Assembly Top")
		(33 "B.Fab" user "Ref Des/Assembly Bottom")
	)
	(footprint ""
		(layer "B.Cu")
		(at 190.114428 -140.46454 90)
		(property "Reference" "R632"
			(at 0 0 90)
			(layer "B.SilkS")
			(hide yes)
			(effects
				(font
					(size 1.27 1.27)
				)
				(justify mirror)
			)
		)
		(property "Value" ""
			(at 0 0 90)
			(layer "B.Fab")
			(effects
				(font
					(size 1.27 1.27)
				)
				(justify mirror)
			)
		)
		(duplicate_pad_numbers_are_jumpers no)
		(fp_line
			(start 0.7874 -0.4064)
			(end -0.7874 -0.4064)
			(stroke
				(width 0.1524)
				(type default)
			)
			(layer "B.SilkS")
		)
		(fp_line
			(start -0.7874 -0.4064)
			(end -0.7874 0.4064)
			(stroke
				(width 0.1524)
				(type default)
			)
			(layer "B.SilkS")
		)
		(fp_line
			(start 0.7874 0.4064)
			(end 0.7874 -0.4064)
			(stroke
				(width 0.1524)
				(type default)
			)
			(layer "B.SilkS")
		)
		(fp_line
			(start -0.7874 0.4064)
			(end 0.7874 0.4064)
			(stroke
				(width 0.1524)
				(type default)
			)
			(layer "B.SilkS")
		)
		(fp_line
			(start 0.67945 -0.305054)
			(end 0.12065 -0.305054)
			(stroke
				(width 0.1)
				(type default)
			)
			(layer "B.Fab")
		)
		(fp_line
			(start 0.12065 -0.305054)
			(end 0.12065 -0.2794)
			(stroke
				(width 0.1)
				(type default)
			)
			(layer "B.Fab")
		)
		(fp_line
			(start -0.12065 -0.3048)
			(end -0.67945 -0.3048)
			(stroke
				(width 0.1)
				(type default)
			)
			(layer "B.Fab")
		)
		(fp_line
			(start -0.67945 -0.3048)
			(end -0.67945 0.3048)
			(stroke
				(width 0.1)
				(type default)
			)
			(layer "B.Fab")
		)
		(fp_line
			(start 0.12065 -0.2794)
			(end -0.12065 -0.2794)
			(stroke
				(width 0.1)
				(type default)
			)
			(layer "B.Fab")
		)
		(fp_line
			(start -0.12065 -0.2794)
			(end -0.12065 -0.3048)
			(stroke
				(width 0.1)
				(type default)
			)
			(layer "B.Fab")
		)
		(fp_line
			(start 0.12065 0.2794)
			(end 0.12065 0.3048)
			(stroke
				(width 0.1)
				(type default)
			)
			(layer "B.Fab")
		)
		(fp_line
			(start -0.120396 0.2794)
			(end 0.12065 0.2794)
			(stroke
				(width 0.1)
				(type default)
			)
			(layer "B.Fab")
		)
		(fp_line
			(start 0.67945 0.3048)
			(end 0.67945 -0.305054)
			(stroke
				(width 0.1)
				(type default)
			)
			(layer "B.Fab")
		)
		(fp_line
			(start 0.12065 0.3048)
			(end 0.67945 0.3048)
			(stroke
				(width 0.1)
				(type default)
			)
			(layer "B.Fab")
		)
		(fp_line
			(start -0.120396 0.3048)
			(end -0.120396 0.2794)
			(stroke
				(width 0.1)
				(type default)
			)
			(layer "B.Fab")
		)
		(fp_line
			(start -0.67945 0.3048)
			(end -0.120396 0.3048)
			(stroke
				(width 0.1)
				(type default)
			)
			(layer "B.Fab")
		)
		(pad "1" smd circle
			(at 0.40005 0 270)
			(size 0 0)
			(layers "B.Cu" "B.Mask" "B.Paste")
			(net "PVDD18_S5_P0")
		)
		(pad "2" smd circle
			(at -0.40005 0 270)
			(size 0 0)
			(layers "B.Cu" "B.Mask" "B.Paste")
			(net "SMB_CPU_5_SCL")
		)
	)
	(footprint ""
		(layer "B.Cu")
		(at 110.276386 -267.529564)
		(property "Reference" "C2359"
			(at 0 0 0)
			(layer "B.SilkS")
			(hide yes)
			(effects
				(font
					(size 1.27 1.27)
				)
				(justify mirror)
			)
		)
		(property "Value" ""
			(at 0 0 0)
			(layer "B.Fab")
			(effects
				(font
					(size 1.27 1.27)
				)
				(justify mirror)
			)
		)
		(duplicate_pad_numbers_are_jumpers no)
		(fp_line
			(start -0.7874 -0.4064)
			(end -0.7874 0.4064)
			(stroke
				(width 0.1524)
				(type default)
			)
			(layer "B.SilkS")
		)
		(fp_line
			(start -0.7874 0.4064)
			(end 0.7874 0.4064)
			(stroke
				(width 0.1524)
				(type default)
			)
			(layer "B.SilkS")
		)
		(fp_line
			(start 0.7874 -0.4064)
			(end -0.7874 -0.4064)
			(stroke
				(width 0.1524)
				(type default)
			)
			(layer "B.SilkS")
		)
		(fp_line
			(start 0.7874 0.4064)
			(end 0.7874 -0.4064)
			(stroke
				(width 0.1524)
				(type default)
			)
			(layer "B.SilkS")
		)
		(fp_line
			(start -0.67945 -0.3048)
			(end -0.67945 0.3048)
			(stroke
				(width 0.1)
				(type default)
			)
			(layer "B.Fab")
		)
		(fp_line
			(start -0.67945 0.3048)
			(end -0.120396 0.3048)
			(stroke
				(width 0.1)
				(type default)
			)
			(layer "B.Fab")
		)
		(fp_line
			(start -0.12065 -0.3048)
			(end -0.67945 -0.3048)
			(stroke
				(width 0.1)
				(type default)
			)
			(layer "B.Fab")
		)
		(fp_line
			(start -0.12065 -0.2794)
			(end -0.12065 -0.3048)
			(stroke
				(width 0.1)
				(type default)
			)
			(layer "B.Fab")
		)
		(fp_line
			(start -0.120396 0.2794)
			(end 0.12065 0.2794)
			(stroke
				(width 0.1)
				(type default)
			)
			(layer "B.Fab")
		)
		(fp_line
			(start -0.120396 0.3048)
			(end -0.120396 0.2794)
			(stroke
				(width 0.1)
				(type default)
			)
			(layer "B.Fab")
		)
		(fp_line
			(start 0.12065 -0.305054)
			(end 0.12065 -0.2794)
			(stroke
				(width 0.1)
				(type default)
			)
			(layer "B.Fab")
		)
		(fp_line
			(start 0.12065 -0.2794)
			(end -0.12065 -0.2794)
			(stroke
				(width 0.1)
				(type default)
			)
			(layer "B.Fab")
		)
		(fp_line
			(start 0.12065 0.2794)
			(end 0.12065 0.3048)
			(stroke
				(width 0.1)
				(type default)
			)
			(layer "B.Fab")
		)
		(fp_line
			(start 0.12065 0.3048)
			(end 0.67945 0.3048)
			(stroke
				(width 0.1)
				(type default)
			)
			(layer "B.Fab")
		)
		(fp_line
			(start 0.67945 -0.305054)
			(end 0.12065 -0.305054)
			(stroke
				(width 0.1)
				(type default)
			)
			(layer "B.Fab")
		)
		(fp_line
			(start 0.67945 0.3048)
			(end 0.67945 -0.305054)
			(stroke
				(width 0.1)
				(type default)
			)
			(layer "B.Fab")
		)
		(pad "1" smd circle
			(at 0.40005 0 180)
			(size 0 0)
			(layers "B.Cu" "B.Mask" "B.Paste")
			(net "PVDDCR_CPU1_P1")
		)
		(pad "2" smd circle
			(at -0.40005 0 180)
			(size 0 0)
			(layers "B.Cu" "B.Mask" "B.Paste")
			(net "GND")
		)
	)
	(footprint ""
		(layer "B.Cu")
		(at 100.497386 -256.734564 180)
		(property "Reference" "C2498"
			(at 0 0 0)
			(layer "B.SilkS")
			(hide yes)
			(effects
				(font
					(size 1.27 1.27)
				)
				(justify mirror)
			)
		)
		(property "Value" ""
			(at 0 0 0)
			(layer "B.Fab")
			(effects
				(font
					(size 1.27 1.27)
				)
				(justify mirror)
			)
		)
		(duplicate_pad_numbers_are_jumpers no)
		(fp_line
			(start 0.7874 0.4064)
			(end 0.7874 -0.4064)
			(stroke
				(width 0.1524)
				(type default)
			)
			(layer "B.SilkS")
		)
		(fp_line
			(start 0.7874 -0.4064)
			(end -0.7874 -0.4064)
			(stroke
				(width 0.1524)
				(type default)
			)
			(layer "B.SilkS")
		)
		(fp_line
			(start -0.7874 0.4064)
			(end 0.7874 0.4064)
			(stroke
				(width 0.1524)
				(type default)
			)
			(layer "B.SilkS")
		)
		(fp_line
			(start -0.7874 -0.4064)
			(end -0.7874 0.4064)
			(stroke
				(width 0.1524)
				(type default)
			)
			(layer "B.SilkS")
		)
		(fp_line
			(start 0.67945 0.3048)
			(end 0.67945 -0.305054)
			(stroke
				(width 0.1)
				(type default)
			)
			(layer "B.Fab")
		)
		(fp_line
			(start 0.67945 -0.305054)
			(end 0.12065 -0.305054)
			(stroke
				(width 0.1)
				(type default)
			)
			(layer "B.Fab")
		)
		(fp_line
			(start 0.12065 0.3048)
			(end 0.67945 0.3048)
			(stroke
				(width 0.1)
				(type default)
			)
			(layer "B.Fab")
		)
		(fp_line
			(start 0.12065 0.2794)
			(end 0.12065 0.3048)
			(stroke
				(width 0.1)
				(type default)
			)
			(layer "B.Fab")
		)
		(fp_line
			(start 0.12065 -0.2794)
			(end -0.12065 -0.2794)
			(stroke
				(width 0.1)
				(type default)
			)
			(layer "B.Fab")
		)
		(fp_line
			(start 0.12065 -0.305054)
			(end 0.12065 -0.2794)
			(stroke
				(width 0.1)
				(type default)
			)
			(layer "B.Fab")
		)
		(fp_line
			(start -0.120396 0.3048)
			(end -0.120396 0.2794)
			(stroke
				(width 0.1)
				(type default)
			)
			(layer "B.Fab")
		)
		(fp_line
			(start -0.120396 0.2794)
			(end 0.12065 0.2794)
			(stroke
				(width 0.1)
				(type default)
			)
			(layer "B.Fab")
		)
		(fp_line
			(start -0.12065 -0.2794)
			(end -0.12065 -0.3048)
			(stroke
				(width 0.1)
				(type default)
			)
			(layer "B.Fab")
		)
		(fp_line
			(start -0.12065 -0.3048)
			(end -0.67945 -0.3048)
			(stroke
				(width 0.1)
				(type default)
			)
			(layer "B.Fab")
		)
		(fp_line
			(start -0.67945 0.3048)
			(end -0.120396 0.3048)
			(stroke
				(width 0.1)
				(type default)
			)
			(layer "B.Fab")
		)
		(fp_line
			(start -0.67945 -0.3048)
			(end -0.67945 0.3048)
			(stroke
				(width 0.1)
				(type default)
			)
			(layer "B.Fab")
		)
		(pad "1" smd circle
			(at 0.40005 0)
			(size 0 0)
			(layers "B.Cu" "B.Mask" "B.Paste")
			(net "PVDDIO_P1")
		)
		(pad "2" smd circle
			(at -0.40005 0)
			(size 0 0)
			(layers "B.Cu" "B.Mask" "B.Paste")
			(net "GND")
		)
	)
	(footprint ""
		(layer "B.Cu")
		(at 393.637008 -322.195952)
		(property "Reference" "R739"
			(at 0 0 0)
			(layer "B.SilkS")
			(hide yes)
			(effects
				(font
					(size 1.27 1.27)
				)
				(justify mirror)
			)
		)
		(property "Value" ""
			(at 0 0 0)
			(layer "B.Fab")
			(effects
				(font
					(size 1.27 1.27)
				)
				(justify mirror)
			)
		)
		(duplicate_pad_numbers_are_jumpers no)
		(fp_line
			(start -0.7874 -0.4064)
			(end -0.7874 0.4064)
			(stroke
				(width 0.1524)
				(type default)
			)
			(layer "B.SilkS")
		)
		(fp_line
			(start -0.7874 0.4064)
			(end 0.7874 0.4064)
			(stroke
				(width 0.1524)
				(type default)
			)
			(layer "B.SilkS")
		)
		(fp_line
			(start 0.7874 -0.4064)
			(end -0.7874 -0.4064)
			(stroke
				(width 0.1524)
				(type default)
			)
			(layer "B.SilkS")
		)
		(fp_line
			(start 0.7874 0.4064)
			(end 0.7874 -0.4064)
			(stroke
				(width 0.1524)
				(type default)
			)
			(layer "B.SilkS")
		)
		(fp_line
			(start -0.67945 -0.3048)
			(end -0.67945 0.3048)
			(stroke
				(width 0.1)
				(type default)
			)
			(layer "B.Fab")
		)
		(fp_line
			(start -0.67945 0.3048)
			(end -0.120396 0.3048)
			(stroke
				(width 0.1)
				(type default)
			)
			(layer "B.Fab")
		)
		(fp_line
			(start -0.12065 -0.3048)
			(end -0.67945 -0.3048)
			(stroke
				(width 0.1)
				(type default)
			)
			(layer "B.Fab")
		)
		(fp_line
			(start -0.12065 -0.2794)
			(end -0.12065 -0.3048)
			(stroke
				(width 0.1)
				(type default)
			)
			(layer "B.Fab")
		)
		(fp_line
			(start -0.120396 0.2794)
			(end 0.12065 0.2794)
			(stroke
				(width 0.1)
				(type default)
			)
			(layer "B.Fab")
		)
		(fp_line
			(start -0.120396 0.3048)
			(end -0.120396 0.2794)
			(stroke
				(width 0.1)
				(type default)
			)
			(layer "B.Fab")
		)
		(fp_line
			(start 0.12065 -0.305054)
			(end 0.12065 -0.2794)
			(stroke
				(width 0.1)
				(type default)
			)
			(layer "B.Fab")
		)
		(fp_line
			(start 0.12065 -0.2794)
			(end -0.12065 -0.2794)
			(stroke
				(width 0.1)
				(type default)
			)
			(layer "B.Fab")
		)
		(fp_line
			(start 0.12065 0.2794)
			(end 0.12065 0.3048)
			(stroke
				(width 0.1)
				(type default)
			)
			(layer "B.Fab")
		)
		(fp_line
			(start 0.12065 0.3048)
			(end 0.67945 0.3048)
			(stroke
				(width 0.1)
				(type default)
			)
			(layer "B.Fab")
		)
		(fp_line
			(start 0.67945 -0.305054)
			(end 0.12065 -0.305054)
			(stroke
				(width 0.1)
				(type default)
			)
			(layer "B.Fab")
		)
		(fp_line
			(start 0.67945 0.3048)
			(end 0.67945 -0.305054)
			(stroke
				(width 0.1)
				(type default)
			)
			(layer "B.Fab")
		)
		(pad "1" smd circle
			(at 0.40005 0 180)
			(size 0 0)
			(layers "B.Cu" "B.Mask" "B.Paste")
			(net "PVDD18_S5_P0")
		)
		(pad "2" smd circle
			(at -0.40005 0 180)
			(size 0 0)
			(layers "B.Cu" "B.Mask" "B.Paste")
			(net "CLK_ESPI_CPU0_CLK1")
		)
	)
	(footprint ""
		(layer "B.Cu")
		(at 435.549802 -12.104116 180)
		(property "Reference" "C1238"
			(at 0 0 0)
			(layer "B.SilkS")
			(hide yes)
			(effects
				(font
					(size 1.27 1.27)
				)
				(justify mirror)
			)
		)
		(property "Value" ""
			(at 0 0 0)
			(layer "B.Fab")
			(effects
				(font
					(size 1.27 1.27)
				)
				(justify mirror)
			)
		)
		(duplicate_pad_numbers_are_jumpers no)
		(fp_line
			(start 0.7874 0.4064)
			(end 0.7874 -0.4064)
			(stroke
				(width 0.1524)
				(type default)
			)
			(layer "B.SilkS")
		)
		(fp_line
			(start 0.7874 -0.4064)
			(end -0.7874 -0.4064)
			(stroke
				(width 0.1524)
				(type default)
			)
			(layer "B.SilkS")
		)
		(fp_line
			(start -0.7874 0.4064)
			(end 0.7874 0.4064)
			(stroke
				(width 0.1524)
				(type default)
			)
			(layer "B.SilkS")
		)
		(fp_line
			(start -0.7874 -0.4064)
			(end -0.7874 0.4064)
			(stroke
				(width 0.1524)
				(type default)
			)
			(layer "B.SilkS")
		)
		(fp_line
			(start 0.67945 0.3048)
			(end 0.67945 -0.305054)
			(stroke
				(width 0.1)
				(type default)
			)
			(layer "B.Fab")
		)
		(fp_line
			(start 0.67945 -0.305054)
			(end 0.12065 -0.305054)
			(stroke
				(width 0.1)
				(type default)
			)
			(layer "B.Fab")
		)
		(fp_line
			(start 0.12065 0.3048)
			(end 0.67945 0.3048)
			(stroke
				(width 0.1)
				(type default)
			)
			(layer "B.Fab")
		)
		(fp_line
			(start 0.12065 0.2794)
			(end 0.12065 0.3048)
			(stroke
				(width 0.1)
				(type default)
			)
			(layer "B.Fab")
		)
		(fp_line
			(start 0.12065 -0.2794)
			(end -0.12065 -0.2794)
			(stroke
				(width 0.1)
				(type default)
			)
			(layer "B.Fab")
		)
		(fp_line
			(start 0.12065 -0.305054)
			(end 0.12065 -0.2794)
			(stroke
				(width 0.1)
				(type default)
			)
			(layer "B.Fab")
		)
		(fp_line
			(start -0.120396 0.3048)
			(end -0.120396 0.2794)
			(stroke
				(width 0.1)
				(type default)
			)
			(layer "B.Fab")
		)
		(fp_line
			(start -0.120396 0.2794)
			(end 0.12065 0.2794)
			(stroke
				(width 0.1)
				(type default)
			)
			(layer "B.Fab")
		)
		(fp_line
			(start -0.12065 -0.2794)
			(end -0.12065 -0.3048)
			(stroke
				(width 0.1)
				(type default)
			)
			(layer "B.Fab")
		)
		(fp_line
			(start -0.12065 -0.3048)
			(end -0.67945 -0.3048)
			(stroke
				(width 0.1)
				(type default)
			)
			(layer "B.Fab")
		)
		(fp_line
			(start -0.67945 0.3048)
			(end -0.120396 0.3048)
			(stroke
				(width 0.1)
				(type default)
			)
			(layer "B.Fab")
		)
		(fp_line
			(start -0.67945 -0.3048)
			(end -0.67945 0.3048)
			(stroke
				(width 0.1)
				(type default)
			)
			(layer "B.Fab")
		)
		(pad "1" smd circle
			(at 0.40005 0)
			(size 0 0)
			(layers "B.Cu" "B.Mask" "B.Paste")
			(net "P3V3_OCP_SFF")
		)
		(pad "2" smd circle
			(at -0.40005 0)
			(size 0 0)
			(layers "B.Cu" "B.Mask" "B.Paste")
			(net "GND")
		)
	)
	(footprint ""
		(layer "B.Cu")
		(at 162.348926 -408.517344 90)
		(property "Reference" "C6756"
			(at 0 0 90)
			(layer "B.SilkS")
			(hide yes)
			(effects
				(font
					(size 1.27 1.27)
				)
				(justify mirror)
			)
		)
		(property "Value" ""
			(at 0 0 90)
			(layer "B.Fab")
			(effects
				(font
					(size 1.27 1.27)
				)
				(justify mirror)
			)
		)
		(duplicate_pad_numbers_are_jumpers no)
		(fp_line
			(start 0.299974 -0.150114)
			(end -0.299974 -0.150114)
			(stroke
				(width 0.1)
				(type default)
			)
			(layer "B.Fab")
		)
		(fp_line
			(start -0.299974 -0.150114)
			(end -0.299974 0.150114)
			(stroke
				(width 0.1)
				(type default)
			)
			(layer "B.Fab")
		)
		(fp_line
			(start 0.299974 0.150114)
			(end 0.299974 -0.150114)
			(stroke
				(width 0.1)
				(type default)
			)
			(layer "B.Fab")
		)
		(fp_line
			(start -0.299974 0.150114)
			(end 0.299974 0.150114)
			(stroke
				(width 0.1)
				(type default)
			)
			(layer "B.Fab")
		)
		(pad "1" smd rect
			(at 0.2667 0 270)
			(size 0.3048 0.381)
			(layers "B.Cu" "B.Mask" "B.Paste")
			(net "P5E_CPU1_P3_TX_BUF_C_DN<15>")
		)
		(pad "2" smd rect
			(at -0.2667 0 270)
			(size 0.3048 0.381)
			(layers "B.Cu" "B.Mask" "B.Paste")
			(net "P5E_CPU1_P3_TX_BUF_DN<15>")
		)
	)
	(footprint ""
		(layer "B.Cu")
		(at 449.79971 -423.935398 180)
		(property "Reference" "PR6618"
			(at 0 0 0)
			(layer "B.SilkS")
			(hide yes)
			(effects
				(font
					(size 1.27 1.27)
				)
				(justify mirror)
			)
		)
		(property "Value" ""
			(at 0 0 0)
			(layer "B.Fab")
			(effects
				(font
					(size 1.27 1.27)
				)
				(justify mirror)
			)
		)
		(duplicate_pad_numbers_are_jumpers no)
		(fp_line
			(start 0.7874 0.4064)
			(end 0.7874 -0.4064)
			(stroke
				(width 0.1524)
				(type default)
			)
			(layer "B.SilkS")
		)
		(fp_line
			(start 0.7874 -0.4064)
			(end -0.7874 -0.4064)
			(stroke
				(width 0.1524)
				(type default)
			)
			(layer "B.SilkS")
		)
		(fp_line
			(start -0.7874 0.4064)
			(end 0.7874 0.4064)
			(stroke
				(width 0.1524)
				(type default)
			)
			(layer "B.SilkS")
		)
		(fp_line
			(start -0.7874 -0.4064)
			(end -0.7874 0.4064)
			(stroke
				(width 0.1524)
				(type default)
			)
			(layer "B.SilkS")
		)
		(fp_line
			(start 0.67945 0.3048)
			(end 0.67945 -0.305054)
			(stroke
				(width 0.1)
				(type default)
			)
			(layer "B.Fab")
		)
		(fp_line
			(start 0.67945 -0.305054)
			(end 0.12065 -0.305054)
			(stroke
				(width 0.1)
				(type default)
			)
			(layer "B.Fab")
		)
		(fp_line
			(start 0.12065 0.3048)
			(end 0.67945 0.3048)
			(stroke
				(width 0.1)
				(type default)
			)
			(layer "B.Fab")
		)
		(fp_line
			(start 0.12065 0.2794)
			(end 0.12065 0.3048)
			(stroke
				(width 0.1)
				(type default)
			)
			(layer "B.Fab")
		)
		(fp_line
			(start 0.12065 -0.2794)
			(end -0.12065 -0.2794)
			(stroke
				(width 0.1)
				(type default)
			)
			(layer "B.Fab")
		)
		(fp_line
			(start 0.12065 -0.305054)
			(end 0.12065 -0.2794)
			(stroke
				(width 0.1)
				(type default)
			)
			(layer "B.Fab")
		)
		(fp_line
			(start -0.120396 0.3048)
			(end -0.120396 0.2794)
			(stroke
				(width 0.1)
				(type default)
			)
			(layer "B.Fab")
		)
		(fp_line
			(start -0.120396 0.2794)
			(end 0.12065 0.2794)
			(stroke
				(width 0.1)
				(type default)
			)
			(layer "B.Fab")
		)
		(fp_line
			(start -0.12065 -0.2794)
			(end -0.12065 -0.3048)
			(stroke
				(width 0.1)
				(type default)
			)
			(layer "B.Fab")
		)
		(fp_line
			(start -0.12065 -0.3048)
			(end -0.67945 -0.3048)
			(stroke
				(width 0.1)
				(type default)
			)
			(layer "B.Fab")
		)
		(fp_line
			(start -0.67945 0.3048)
			(end -0.120396 0.3048)
			(stroke
				(width 0.1)
				(type default)
			)
			(layer "B.Fab")
		)
		(fp_line
			(start -0.67945 -0.3048)
			(end -0.67945 0.3048)
			(stroke
				(width 0.1)
				(type default)
			)
			(layer "B.Fab")
		)
		(pad "1" smd circle
			(at 0.40005 0)
			(size 0 0)
			(layers "B.Cu" "B.Mask" "B.Paste")
			(net "P0V9_RETIMER_CPU0_TEMP1_R")
		)
		(pad "2" smd circle
			(at -0.40005 0)
			(size 0 0)
			(layers "B.Cu" "B.Mask" "B.Paste")
			(net "GND")
		)
	)
)
